FILE_TYPE = CONNECTIVITY;
{Allegro Design Entry HDL 17.4-2019 S026 (4007227) 1/17/2022}
"PAGE_NUMBER" = 409;
0"NC";
1"GND\g";
2"GND\g";
3"P1V8_CPU0_RT_1D\g";
4"GND\g";
5"RT_CPU0_P1_VQPS";
6"P1V8_CPU0_RT1_1A_1D\g";
7"P0V9_CPU0_RT_2D\g";
8"P0V9_CPU0_RT1_2A\g";
9"P0V9_CPU0_RT1_2A_2D\g";
10"GND\g";
11"GND\g";
12"NCF_CPU0_P1_GND";
13"P1V8_CPU0_RT1_1A\g";
14"NCF_A1_CPU0_P1_GND";
%"VCC_CORE"
"1","(-4900,5025)","0","pure_quanta_power","I10";
;
HDL_POWER"P0V9_CPU0_RT1_2A"
CDS_LIB"pure_quanta_power";
"A"8;
%"UNIVERSAL_GND"
"1","(-3350,1325)","0","pure_quanta_power","I11";
;
CDS_LIB"pure_quanta_power"
HDL_POWER"GND";
"A"10;
%"UNIVERSAL_GND"
"1","(-1675,950)","0","pure_quanta_power","I12";
;
CDS_LIB"pure_quanta_power"
HDL_POWER"GND";
"A"1;
%"Q_RES"
"2","(-1675,1250)","0","pure_quanta","I13";
;
LOCATION"R1042"
$SEC"1"
CDS_SEC"1"
MATERIAL"CHIP"
WATTAGE"1/20W"
TOLERANCE"5%"
VALUE"0"
PACK_TYPE"0201LF"
CDS_LIB"pure_quanta"
PART_NUMBER"CS00001JE10";
"A"
$PN"1"12;
"B"
$PN"2"1;
%"UNIVERSAL_GND"
"1","(-1525,1500)","0","pure_quanta_power","I14";
;
CDS_LIB"pure_quanta_power"
HDL_POWER"GND";
"A"2;
%"Q_RES"
"2","(-1525,1800)","0","pure_quanta","I15";
;
LOCATION"R1043"
$SEC"1"
CDS_SEC"1"
WATTAGE"1/20W"
TOLERANCE"5%"
MATERIAL"CHIP"
PACK_TYPE"0201LF"
VALUE"0"
CDS_LIB"pure_quanta"
PART_NUMBER"CS00001JE10";
"A"
$PN"1"14;
"B"
$PN"2"2;
%"UNIVERSAL_GND"
"1","(-1300,2050)","0","pure_quanta_power","I16";
;
CDS_LIB"pure_quanta_power"
HDL_POWER"GND";
"A"11;
%"PT5161LRS"
"5","(-2650,3575)","0","pure_quanta","I17";
;
LOCATION"U6011"
$SEC"5"
CDS_SEC"5"
PART_TYPE"SMLF"
MATERIAL"IC"
VALUE"PT5161LRS"
NEEDS_NO_SIZE"TRUE"
CDS_LMAN_SYM_OUTLINE"-350,2150,300,-2150"
CDS_LIB"pure_quanta"
PART_NUMBER"AJ051610U03";
"GND151"
$PN"V35"11;
"GND150"
$PN"V1"11;
"GND149"
$PN"U34"11;
"GND148"
$PN"U2"11;
"GND147"
$PN"T4"11;
"GND146"
$PN"T32"11;
"GND145"
$PN"T22"11;
"GND144"
$PN"T13"11;
"GND143"
$PN"L35"11;
"GND142"
$PN"L1"11;
"GND141"
$PN"K34"11;
"GND140"
$PN"K2"11;
"GND139"
$PN"J4"11;
"GND138"
$PN"J22"11;
"GND137"
$PN"H31"11;
"GND136"
$PN"H19"11;
"GND135"
$PN"H16"11;
"GND134"
$PN"H12"11;
"GND133"
$PN"FJ19"11;
"GND132"
$PN"FJ12"11;
"GND131"
$PN"FF21"11;
"GND130"
$PN"FF14"11;
"GND129"
$PN"FD35"11;
"GND128"
$PN"FD1"11;
"GND127"
$PN"FC9"11;
"GND126"
$PN"FC6"11;
"GND125"
$PN"FC3"11;
"GND124"
$PN"FC28"11;
"GND123"
$PN"FC25"11;
"GND122"
$PN"FC23"11;
"GND121"
$PN"FC19"11;
"GND120"
$PN"FB34"11;
"GND119"
$PN"FB2"11;
"GND118"
$PN"FA32"11;
"GND117"
$PN"FA15"11;
"GND116"
$PN"ET35"11;
"GND115"
$PN"ET1"11;
"GND114"
$PN"ER34"11;
"GND113"
$PN"ER2"11;
"GND112"
$PN"EP4"11;
"GND111"
$PN"EP32"11;
"GND110"
$PN"EP22"11;
"GND109"
$PN"EP13"11;
"GND108"
$PN"EJ35"11;
"GND107"
$PN"EJ1"11;
"GND106"
$PN"EH34"11;
"GND105"
$PN"EH2"11;
"GND104"
$PN"EG4"11;
"GND103"
$PN"EG32"11;
"GND102"
$PN"EG22"11;
"GND101"
$PN"EG13"11;
"GND100"
$PN"EB35"11;
"GND99"
$PN"EB1"11;
"GND98"
$PN"EA34"11;
"GND97"
$PN"EA2"11;
"GND96"
$PN"E33"11;
"GND95"
$PN"E27"11;
"GND94"
$PN"E14"11;
"GND93"
$PN"DY4"11;
"GND92"
$PN"DY32"11;
"GND91"
$PN"DY22"11;
"GND90"
$PN"DY13"11;
"GND89"
$PN"DR35"11;
"GND88"
$PN"DR1"11;
"GND87"
$PN"DP34"11;
"GND86"
$PN"DP2"11;
"GND85"
$PN"DN4"11;
"GND84"
$PN"DN32"11;
"GND83"
$PN"DN22"11;
"NCF_GND12"
$PN"FH34"12;
"NCF_GND11"
$PN"FH2"12;
"NCF_GND10"
$PN"FG35"12;
"NCF_GND9"
$PN"FG1"12;
"NCF_GND8"
$PN"FE34"12;
"NCF_GND7"
$PN"FE2"12;
"NCF_GND6"
$PN"D35"12;
"NCF_GND5"
$PN"D1"12;
"NCF_GND4"
$PN"C34"12;
"NCF_GND3"
$PN"C2"12;
"NCF_GND2"
$PN"A35"12;
"NCF_GND1"
$PN"A1"14;
"GND82"
$PN"DN13"10;
"GND81"
$PN"DH35"10;
"GND80"
$PN"DH1"10;
"GND79"
$PN"DG34"10;
"GND78"
$PN"DG2"10;
"GND77"
$PN"DF4"10;
"GND76"
$PN"DF32"10;
"GND75"
$PN"DF22"10;
"GND74"
$PN"DF13"10;
"GND73"
$PN"DA35"10;
"GND72"
$PN"DA1"10;
"GND71"
$PN"CY34"10;
"GND70"
$PN"CY2"10;
"GND69"
$PN"CW4"10;
"GND68"
$PN"CW32"10;
"GND67"
$PN"CW22"10;
"GND66"
$PN"CW13"10;
"GND65"
$PN"CP35"10;
"GND64"
$PN"CP1"10;
"GND63"
$PN"CN34"10;
"GND62"
$PN"CN2"10;
"GND61"
$PN"CM4"10;
"GND60"
$PN"CM32"10;
"GND59"
$PN"CM22"10;
"GND58"
$PN"CM13"10;
"GND57"
$PN"CG35"10;
"GND56"
$PN"CG1"10;
"GND55"
$PN"CF34"10;
"GND54"
$PN"CF2"10;
"GND53"
$PN"CE4"10;
"GND52"
$PN"CE32"10;
"GND51"
$PN"CE22"10;
"GND50"
$PN"CE13"10;
"GND49"
$PN"BY35"10;
"GND48"
$PN"BY1"10;
"GND47"
$PN"BW34"10;
"GND46"
$PN"BW2"10;
"GND45"
$PN"BV4"10;
"GND44"
$PN"BV32"10;
"GND43"
$PN"BV22"10;
"GND42"
$PN"BV13"10;
"GND41"
$PN"BN35"10;
"GND40"
$PN"BN1"10;
"GND39"
$PN"BM34"10;
"GND38"
$PN"BM2"10;
"GND37"
$PN"BL4"10;
"GND36"
$PN"BL32"10;
"GND35"
$PN"BL22"10;
"GND34"
$PN"BL13"10;
"GND33"
$PN"BF35"10;
"GND32"
$PN"BF1"10;
"GND31"
$PN"BE34"10;
"GND30"
$PN"BE2"10;
"GND29"
$PN"BD4"10;
"GND28"
$PN"BD32"10;
"GND27"
$PN"BD22"10;
"GND26"
$PN"BD13"10;
"GND25"
$PN"B19"10;
"GND24"
$PN"AW35"10;
"GND23"
$PN"AW1"10;
"GND22"
$PN"AV34"10;
"GND21"
$PN"AV2"10;
"GND20"
$PN"AU4"10;
"GND19"
$PN"AU32"10;
"GND18"
$PN"AU22"10;
"GND17"
$PN"AU13"10;
"GND16"
$PN"AM35"10;
"GND15"
$PN"AM1"10;
"GND14"
$PN"AL34"10;
"GND13"
$PN"AL2"10;
"GND12"
$PN"AK4"10;
"GND11"
$PN"AK32"10;
"GND10"
$PN"AK22"10;
"GND9"
$PN"AK13"10;
"GND8"
$PN"AE35"10;
"GND7"
$PN"AE1"10;
"GND6"
$PN"AD34"10;
"GND5"
$PN"AD2"10;
"GND4"
$PN"AC4"10;
"GND3"
$PN"AC32"10;
"GND2"
$PN"AC22"10;
"GND1"
$PN"AC13"10;
%"Q_RES"
"2","(-7875,3350)","0","pure_quanta","I18";
;
LOCATION"R1041"
$SEC"1"
CDS_SEC"1"
PACK_TYPE"0201LF"
VALUE"200"
TOLERANCE"1%"
WATTAGE"1/20W"
MATERIAL"CHIP"
CDS_LIB"pure_quanta"
PART_NUMBER"CS12001FE12";
"A"
$PN"1"5;
"B"
$PN"2"4;
%"Q_RES"
"2","(-8900,3900)","0","pure_quanta","I19";
;
LOCATION"R1040"
$SEC"1"
CDS_SEC"1"
MATERIAL"EMPTY"
VALUE"1K"
TOLERANCE"1%"
PACK_TYPE"0201LF"
WATTAGE"1/20W"
CDS_LIB"pure_quanta"
PART_NUMBER"CS21001FE07";
"A"
$PN"1"3;
"B"
$PN"2"5;
%"P1V0"
"1","(-8900,4125)","0","pure_quanta_power","I2";
;
HDL_POWER"P1V8_CPU0_RT_1D"
CDS_LIB"pure_quanta_power";
"A"3;
%"UNIVERSAL_GND"
"1","(-7875,3100)","0","pure_quanta_power","I3";
;
CDS_LIB"pure_quanta_power"
HDL_POWER"GND";
"A"4;
%"PT5161LRS"
"4","(-6725,4150)","0","pure_quanta","I5";
;
LOCATION"U6011"
$SEC"4"
CDS_SEC"4"
VALUE"PT5161LRS"
PART_TYPE"SMLF"
MATERIAL"IC"
NEEDS_NO_SIZE"TRUE"
CDS_LMAN_SYM_OUTLINE"-450,750,400,-750"
CDS_LIB"pure_quanta"
PART_NUMBER"AJ051610U03";
"PWR_2A_20"
$PN"T20"8;
"PWR_2A_19"
$PN"T17"8;
"PWR_2A_18"
$PN"EP20"8;
"PWR_2A_17"
$PN"EP17"8;
"PWR_2A_16"
$PN"EG20"8;
"PWR_2A_15"
$PN"EG17"8;
"PWR_2A_14"
$PN"DY20"8;
"PWR_2A_13"
$PN"DY17"8;
"PWR_2A_12"
$PN"DN20"8;
"PWR_2A_11"
$PN"DN17"8;
"PWR_2A_10"
$PN"DF20"9;
"PWR_2A_9"
$PN"DF17"9;
"PWR_2A_8"
$PN"BD20"9;
"PWR_2A_7"
$PN"BD17"9;
"PWR_2A_6"
$PN"AU20"8;
"PWR_2A_5"
$PN"AU17"8;
"PWR_2A_4"
$PN"AK20"8;
"PWR_2A_3"
$PN"AK17"8;
"PWR_2A_2"
$PN"AC20"8;
"PWR_2A_1"
$PN"AC17"8;
"PWR_1D"
$PN"BV17"6;
"PWR_2D_4"
$PN"CW20"7;
"PWR_2D_3"
$PN"CW17"7;
"PWR_2D_2"
$PN"BL20"7;
"PWR_2D_1"
$PN"BL17"7;
"PWR_1A_5"
$PN"CM20"13;
"PWR_1A_4"
$PN"CM17"13;
"PWR_1A_3"
$PN"CE20"13;
"PWR_1A_2"
$PN"CE17"13;
"PWR_1A_1"
$PN"BV20"13;
"VQPS"
$PN"G1"5;
%"P1V0"
"1","(-4875,3800)","0","pure_quanta_power","I6";
;
HDL_POWER"P0V9_CPU0_RT_2D"
CDS_LIB"pure_quanta_power";
"A"7;
%"P1V0"
"1","(-8575,4400)","0","pure_quanta_power","I7";
;
HDL_POWER"P1V8_CPU0_RT1_1A_1D"
CDS_LIB"pure_quanta_power";
"A"6;
%"P1V0"
"1","(-8000,4850)","0","pure_quanta_power","I8";
;
HDL_POWER"P1V8_CPU0_RT1_1A"
CDS_LIB"pure_quanta_power";
"A"13;
%"VCC_CORE"
"1","(-5475,4550)","0","pure_quanta_power","I9";
;
HDL_POWER"P0V9_CPU0_RT1_2A_2D"
CDS_LIB"pure_quanta_power";
"A"9;
END.
